(kicad_pcb
	(version 20260206)
	(generator "pcbnew")
	(generator_version "10.0")
	(general
		(thickness 1.6)
		(legacy_teardrops no)
	)
	(paper "A4")
	(title_block
		(title "Bryce Canyon_IOM_IOC_16318-2_OCP.brd")
		(comment 1 "Bryce Canyon / footprints 942-949 of 1605")
	)
	(layers
		(0 "F.Cu" signal "TOP")
		(4 "In1.Cu" signal "L2GND")
		(6 "In2.Cu" signal "L3")
		(8 "In3.Cu" signal "L4VCC")
		(10 "In4.Cu" signal "L5VCC")
		(12 "In5.Cu" signal "L6")
		(14 "In6.Cu" signal "L7GND")
		(2 "B.Cu" signal "BOTTOM")
		(9 "F.Adhes" user "F.Adhesive")
		(11 "B.Adhes" user "B.Adhesive")
		(13 "F.Paste" user "Package Geometry/Pastemask Top")
		(15 "B.Paste" user "Package Geometry/Pastemask Bottom")
		(5 "F.SilkS" user "Ref Des/Silkscreen Top")
		(7 "B.SilkS" user "Ref Des/Silkscreen Bottom")
		(1 "F.Mask" user "Board Geometry/Soldermask Top")
		(3 "B.Mask" user "Board Geometry/Soldermask Bottom")
		(17 "Dwgs.User" user "User.Drawings")
		(19 "Cmts.User" user "User.Comments")
		(21 "Eco1.User" user "User.Eco1")
		(23 "Eco2.User" user "User.Eco2")
		(25 "Edge.Cuts" user "Board Geometry/Outline")
		(27 "Margin" user)
		(31 "F.CrtYd" user "Package Geometry/Place Bound Top")
		(29 "B.CrtYd" user "Package Geometry/Place Bound Bottom")
		(35 "F.Fab" user "Ref Des/Assembly Top")
		(33 "B.Fab" user "Ref Des/Assembly Bottom")
	)
	(footprint ""
		(layer "F.Cu")
		(at 124.0282 -12.4714 90)
		(property "Reference" "R439"
			(at 0 0 90)
			(layer "F.SilkS")
			(hide yes)
			(effects
				(font
					(size 1.27 1.27)
				)
			)
		)
		(property "Value" "11KR2F-L-GP"
			(at 0.064008 -3.993896 90)
			(unlocked yes)
			(layer "F.Fab")
			(hide yes)
			(effects
				(font
					(size 1.016 1.016)
					(thickness 0.1524)
				)
			)
		)
		(property "Device Type" "R402H16"
			(at 0.064008 -5.517896 90)
			(unlocked yes)
			(layer "F.Fab")
			(hide yes)
			(effects
				(font
					(size 1.016 1.016)
					(thickness 0.1524)
				)
			)
		)
		(duplicate_pad_numbers_are_jumpers no)
		(fp_line
			(start 0.508 -0.9398)
			(end -0.508 -0.9398)
			(stroke
				(width 0.1524)
				(type default)
			)
			(layer "F.SilkS")
		)
		(fp_line
			(start -0.508 -0.9398)
			(end -0.508 0.9398)
			(stroke
				(width 0.1524)
				(type default)
			)
			(layer "F.SilkS")
		)
		(fp_rect
			(start -0.508 0.9398)
			(end 0.508 -0.9398)
			(stroke
				(width 0)
				(type default)
			)
			(fill no)
			(layer "F.CrtYd")
		)
		(fp_rect
			(start -0.508 0.9398)
			(end 0.508 -0.9398)
			(stroke
				(width 0)
				(type default)
			)
			(fill no)
			(layer "F.Fab")
		)
		(pad "1" smd custom
			(at 0 -0.4445 90)
			(size 0.1397 0.1397)
			(layers "F.Cu" "F.Mask" "F.Paste")
			(net "MB0_P12V_PWGIN_R")
			(options
				(clearance outline)
				(anchor circle)
			)
			(primitives
				(gr_poly
					(pts
						(arc
							(start -0.1778 -0.2794)
							(mid -0.249642 -0.249642)
							(end -0.2794 -0.1778)
						)
						(arc
							(start -0.2794 0.1778)
							(mid -0.249642 0.249642)
							(end -0.1778 0.2794)
						)
						(arc
							(start 0.1778 0.2794)
							(mid 0.249642 0.249642)
							(end 0.2794 0.1778)
						)
						(arc
							(start 0.2794 -0.1778)
							(mid 0.249642 -0.249642)
							(end 0.1778 -0.2794)
						)
					)
					(width 0)
					(fill yes)
				)
			)
		)
		(pad "2" smd custom
			(at 0 0.4445 90)
			(size 0.1397 0.1397)
			(layers "F.Cu" "F.Mask" "F.Paste")
			(net "GND")
			(options
				(clearance outline)
				(anchor circle)
			)
			(primitives
				(gr_poly
					(pts
						(arc
							(start -0.1778 -0.2794)
							(mid -0.249642 -0.249642)
							(end -0.2794 -0.1778)
						)
						(arc
							(start -0.2794 0.1778)
							(mid -0.249642 0.249642)
							(end -0.1778 0.2794)
						)
						(arc
							(start 0.1778 0.2794)
							(mid 0.249642 0.249642)
							(end 0.2794 0.1778)
						)
						(arc
							(start 0.2794 -0.1778)
							(mid 0.249642 -0.249642)
							(end 0.1778 -0.2794)
						)
					)
					(width 0)
					(fill yes)
				)
			)
		)
	)
	(footprint ""
		(layer "F.Cu")
		(at 172.6692 -156.7688 180)
		(property "Reference" "L7"
			(at 0 0 180)
			(layer "F.SilkS")
			(hide yes)
			(effects
				(font
					(size 1.27 1.27)
				)
			)
		)
		(property "Value" "IND-4D7UH-291-GP"
			(at -6.34492 -3.502152 180)
			(unlocked yes)
			(layer "F.Fab")
			(hide yes)
			(effects
				(font
					(size 1.016 1.016)
					(thickness 0.1524)
				)
			)
		)
		(property "Device Type" "L11102530H158"
			(at -6.3246 -5.08 180)
			(unlocked yes)
			(layer "F.Fab")
			(hide yes)
			(effects
				(font
					(size 1.016 1.016)
					(thickness 0.1524)
				)
			)
		)
		(duplicate_pad_numbers_are_jumpers no)
		(fp_line
			(start 5.2578 6.3754)
			(end 5.2578 -6.3754)
			(stroke
				(width 0.1524)
				(type default)
			)
			(layer "F.SilkS")
		)
		(fp_line
			(start 5.2578 -6.3754)
			(end -5.2578 -6.3754)
			(stroke
				(width 0.1524)
				(type default)
			)
			(layer "F.SilkS")
		)
		(fp_line
			(start -5.2578 6.3754)
			(end 5.2578 6.3754)
			(stroke
				(width 0.1524)
				(type default)
			)
			(layer "F.SilkS")
		)
		(fp_line
			(start -5.2578 -6.3754)
			(end -5.2578 6.3754)
			(stroke
				(width 0.1524)
				(type default)
			)
			(layer "F.SilkS")
		)
		(fp_rect
			(start -5.0038 5.4991)
			(end 5.0038 -5.4991)
			(stroke
				(width 0)
				(type default)
			)
			(fill no)
			(layer "F.CrtYd")
		)
		(fp_poly
			(pts
				(xy -5.5118 6.4516) (xy -5.5118 -6.4516) (xy 5.5118 -6.4516) (xy 5.5118 -0.8509) (xy 5.0038 -0.8509)
				(xy 5.0038 -5.4991) (xy -5.0038 -5.4991) (xy -5.0038 5.4991) (xy 5.0038 5.4991) (xy 5.0038 -0.8382)
				(xy 5.5118 -0.8382) (xy 5.5118 6.4516)
			)
			(stroke
				(width 0)
				(type default)
			)
			(fill no)
			(layer "F.CrtYd")
		)
		(fp_rect
			(start -5.5118 6.4516)
			(end 5.5118 -6.4516)
			(stroke
				(width 0)
				(type default)
			)
			(fill no)
			(layer "F.Fab")
		)
		(pad "1" smd rect
			(at 0 -4.435094 180)
			(size 3.2512 3.3782)
			(layers "F.Cu" "F.Mask" "F.Paste")
			(net "P5V_LL")
		)
		(pad "2" smd rect
			(at 0 4.435094 180)
			(size 3.2512 3.3782)
			(layers "F.Cu" "F.Mask" "F.Paste")
			(net "P5V_STBY")
		)
	)
	(footprint ""
		(layer "F.Cu")
		(at 68.3006 -183.769 -90)
		(property "Reference" "R510"
			(at 0 0 270)
			(layer "F.SilkS")
			(hide yes)
			(effects
				(font
					(size 1.27 1.27)
				)
			)
		)
		(property "Value" "0R2J-2-GP"
			(at 0.064008 -3.993896 270)
			(unlocked yes)
			(layer "F.Fab")
			(hide yes)
			(effects
				(font
					(size 1.016 1.016)
					(thickness 0.1524)
				)
			)
		)
		(property "Device Type" "R402H16"
			(at 0.064008 -5.517896 270)
			(unlocked yes)
			(layer "F.Fab")
			(hide yes)
			(effects
				(font
					(size 1.016 1.016)
					(thickness 0.1524)
				)
			)
		)
		(duplicate_pad_numbers_are_jumpers no)
		(fp_line
			(start -0.508 -0.9398)
			(end -0.508 0.9398)
			(stroke
				(width 0.1524)
				(type default)
			)
			(layer "F.SilkS")
		)
		(fp_line
			(start 0.508 -0.9398)
			(end -0.508 -0.9398)
			(stroke
				(width 0.1524)
				(type default)
			)
			(layer "F.SilkS")
		)
		(fp_rect
			(start -0.508 0.9398)
			(end 0.508 -0.9398)
			(stroke
				(width 0)
				(type default)
			)
			(fill no)
			(layer "F.CrtYd")
		)
		(fp_rect
			(start -0.508 0.9398)
			(end 0.508 -0.9398)
			(stroke
				(width 0)
				(type default)
			)
			(fill no)
			(layer "F.Fab")
		)
		(pad "1" smd custom
			(at 0 -0.4445 270)
			(size 0.1397 0.1397)
			(layers "F.Cu" "F.Mask" "F.Paste")
			(net "TPS74801_P2V5_STBY_EN")
			(options
				(clearance outline)
				(anchor circle)
			)
			(primitives
				(gr_poly
					(pts
						(arc
							(start -0.1778 -0.2794)
							(mid -0.249642 -0.249642)
							(end -0.2794 -0.1778)
						)
						(arc
							(start -0.2794 0.1778)
							(mid -0.249642 0.249642)
							(end -0.1778 0.2794)
						)
						(arc
							(start 0.1778 0.2794)
							(mid 0.249642 0.249642)
							(end 0.2794 0.1778)
						)
						(arc
							(start 0.2794 -0.1778)
							(mid 0.249642 -0.249642)
							(end 0.1778 -0.2794)
						)
					)
					(width 0)
					(fill yes)
				)
			)
		)
		(pad "2" smd custom
			(at 0 0.4445 270)
			(size 0.1397 0.1397)
			(layers "F.Cu" "F.Mask" "F.Paste")
			(net "PWRGD_P3V3_STBY")
			(options
				(clearance outline)
				(anchor circle)
			)
			(primitives
				(gr_poly
					(pts
						(arc
							(start -0.1778 -0.2794)
							(mid -0.249642 -0.249642)
							(end -0.2794 -0.1778)
						)
						(arc
							(start -0.2794 0.1778)
							(mid -0.249642 0.249642)
							(end -0.1778 0.2794)
						)
						(arc
							(start 0.1778 0.2794)
							(mid 0.249642 0.249642)
							(end 0.2794 0.1778)
						)
						(arc
							(start 0.2794 -0.1778)
							(mid 0.249642 -0.249642)
							(end 0.1778 -0.2794)
						)
					)
					(width 0)
					(fill yes)
				)
			)
		)
	)
	(footprint ""
		(layer "F.Cu")
		(at 68.6054 -118.2116 90)
		(property "Reference" "C74"
			(at 0 0 90)
			(layer "F.SilkS")
			(hide yes)
			(effects
				(font
					(size 1.27 1.27)
				)
			)
		)
		(property "Value" "SCD1U16V2KX-3GP"
			(at 1.1811 -2.7051 90)
			(unlocked yes)
			(layer "F.Fab")
			(hide yes)
			(effects
				(font
					(size 1.016 1.016)
					(thickness 0.1524)
				)
			)
		)
		(property "Device Type" "C402H22"
			(at 1.1811 -4.2291 90)
			(unlocked yes)
			(layer "F.Fab")
			(hide yes)
			(effects
				(font
					(size 1.016 1.016)
					(thickness 0.1524)
				)
			)
		)
		(duplicate_pad_numbers_are_jumpers no)
		(fp_rect
			(start -0.4318 0.9525)
			(end 0.4318 -0.9525)
			(stroke
				(width 0)
				(type default)
			)
			(fill no)
			(layer "F.CrtYd")
		)
		(fp_rect
			(start -0.4318 0.9525)
			(end 0.4318 -0.9525)
			(stroke
				(width 0)
				(type default)
			)
			(fill no)
			(layer "F.Fab")
		)
		(pad "1" smd custom
			(at 0 -0.4445 90)
			(size 0.1524 0.1524)
			(layers "F.Cu" "F.Mask" "F.Paste")
			(net "P3V3_STBY")
			(options
				(clearance outline)
				(anchor circle)
			)
			(primitives
				(gr_poly
					(pts
						(arc
							(start 0.3048 -0.2032)
							(mid 0.275042 -0.275042)
							(end 0.2032 -0.3048)
						)
						(arc
							(start -0.2032 -0.3048)
							(mid -0.275042 -0.275042)
							(end -0.3048 -0.2032)
						)
						(arc
							(start -0.3048 0.2032)
							(mid -0.275042 0.275042)
							(end -0.2032 0.3048)
						)
						(arc
							(start 0.2032 0.3048)
							(mid 0.275042 0.275042)
							(end 0.3048 0.2032)
						)
					)
					(width 0)
					(fill yes)
				)
			)
		)
		(pad "2" smd custom
			(at 0 0.4445 90)
			(size 0.1524 0.1524)
			(layers "F.Cu" "F.Mask" "F.Paste")
			(net "GND")
			(options
				(clearance outline)
				(anchor circle)
			)
			(primitives
				(gr_poly
					(pts
						(arc
							(start 0.3048 -0.2032)
							(mid 0.275042 -0.275042)
							(end 0.2032 -0.3048)
						)
						(arc
							(start -0.2032 -0.3048)
							(mid -0.275042 -0.275042)
							(end -0.3048 -0.2032)
						)
						(arc
							(start -0.3048 0.2032)
							(mid -0.275042 0.275042)
							(end -0.2032 0.3048)
						)
						(arc
							(start 0.2032 0.3048)
							(mid 0.275042 0.275042)
							(end 0.3048 0.2032)
						)
					)
					(width 0)
					(fill yes)
				)
			)
		)
	)
	(footprint ""
		(layer "B.Cu")
		(at 189.1919 -63.4746 90)
		(property "Reference" "C426"
			(at 0 0 90)
			(layer "B.SilkS")
			(hide yes)
			(effects
				(font
					(size 1.27 1.27)
				)
				(justify mirror)
			)
		)
		(property "Value" "SC1KP50V2KX-1GP"
			(at -1.1811 -2.7051 90)
			(unlocked yes)
			(layer "B.Fab")
			(hide yes)
			(effects
				(font
					(size 1.016 1.016)
					(thickness 0.1524)
				)
				(justify mirror)
			)
		)
		(property "Device Type" "C402H22"
			(at -1.1811 -4.2291 90)
			(unlocked yes)
			(layer "B.Fab")
			(hide yes)
			(effects
				(font
					(size 1.016 1.016)
					(thickness 0.1524)
				)
				(justify mirror)
			)
		)
		(duplicate_pad_numbers_are_jumpers no)
		(fp_rect
			(start 0.4318 0.9525)
			(end -0.4318 -0.9525)
			(stroke
				(width 0)
				(type default)
			)
			(fill no)
			(layer "B.CrtYd")
		)
		(fp_rect
			(start 0.4318 0.9525)
			(end -0.4318 -0.9525)
			(stroke
				(width 0)
				(type default)
			)
			(fill no)
			(layer "B.Fab")
		)
		(pad "1" smd custom
			(at 0 -0.4445 270)
			(size 0.1524 0.1524)
			(layers "B.Cu" "B.Mask" "B.Paste")
			(net "P0V975")
			(options
				(clearance outline)
				(anchor circle)
			)
			(primitives
				(gr_poly
					(pts
						(arc
							(start 0.3048 0.2032)
							(mid 0.275042 0.275042)
							(end 0.2032 0.3048)
						)
						(arc
							(start -0.2032 0.3048)
							(mid -0.275042 0.275042)
							(end -0.3048 0.2032)
						)
						(arc
							(start -0.3048 -0.2032)
							(mid -0.275042 -0.275042)
							(end -0.2032 -0.3048)
						)
						(arc
							(start 0.2032 -0.3048)
							(mid 0.275042 -0.275042)
							(end 0.3048 -0.2032)
						)
					)
					(width 0)
					(fill yes)
				)
			)
		)
		(pad "2" smd custom
			(at 0 0.4445 270)
			(size 0.1524 0.1524)
			(layers "B.Cu" "B.Mask" "B.Paste")
			(net "GND")
			(options
				(clearance outline)
				(anchor circle)
			)
			(primitives
				(gr_poly
					(pts
						(arc
							(start 0.3048 0.2032)
							(mid 0.275042 0.275042)
							(end 0.2032 0.3048)
						)
						(arc
							(start -0.2032 0.3048)
							(mid -0.275042 0.275042)
							(end -0.3048 0.2032)
						)
						(arc
							(start -0.3048 -0.2032)
							(mid -0.275042 -0.275042)
							(end -0.2032 -0.3048)
						)
						(arc
							(start 0.2032 -0.3048)
							(mid 0.275042 -0.275042)
							(end 0.3048 -0.2032)
						)
					)
					(width 0)
					(fill yes)
				)
			)
		)
	)
	(footprint ""
		(layer "B.Cu")
		(at 184.0611 -65.1637 90)
		(property "Reference" "C475"
			(at 0 0 90)
			(layer "B.SilkS")
			(hide yes)
			(effects
				(font
					(size 1.27 1.27)
				)
				(justify mirror)
			)
		)
		(property "Value" "SC1KP50V2KX-1GP"
			(at -1.1811 -2.7051 90)
			(unlocked yes)
			(layer "B.Fab")
			(hide yes)
			(effects
				(font
					(size 1.016 1.016)
					(thickness 0.1524)
				)
				(justify mirror)
			)
		)
		(property "Device Type" "C402H22"
			(at -1.1811 -4.2291 90)
			(unlocked yes)
			(layer "B.Fab")
			(hide yes)
			(effects
				(font
					(size 1.016 1.016)
					(thickness 0.1524)
				)
				(justify mirror)
			)
		)
		(duplicate_pad_numbers_are_jumpers no)
		(fp_rect
			(start 0.4318 0.9525)
			(end -0.4318 -0.9525)
			(stroke
				(width 0)
				(type default)
			)
			(fill no)
			(layer "B.CrtYd")
		)
		(fp_rect
			(start 0.4318 0.9525)
			(end -0.4318 -0.9525)
			(stroke
				(width 0)
				(type default)
			)
			(fill no)
			(layer "B.Fab")
		)
		(pad "1" smd custom
			(at 0 -0.4445 270)
			(size 0.1524 0.1524)
			(layers "B.Cu" "B.Mask" "B.Paste")
			(net "P1V8")
			(options
				(clearance outline)
				(anchor circle)
			)
			(primitives
				(gr_poly
					(pts
						(arc
							(start 0.3048 0.2032)
							(mid 0.275042 0.275042)
							(end 0.2032 0.3048)
						)
						(arc
							(start -0.2032 0.3048)
							(mid -0.275042 0.275042)
							(end -0.3048 0.2032)
						)
						(arc
							(start -0.3048 -0.2032)
							(mid -0.275042 -0.275042)
							(end -0.2032 -0.3048)
						)
						(arc
							(start 0.2032 -0.3048)
							(mid 0.275042 -0.275042)
							(end 0.3048 -0.2032)
						)
					)
					(width 0)
					(fill yes)
				)
			)
		)
		(pad "2" smd custom
			(at 0 0.4445 270)
			(size 0.1524 0.1524)
			(layers "B.Cu" "B.Mask" "B.Paste")
			(net "GND")
			(options
				(clearance outline)
				(anchor circle)
			)
			(primitives
				(gr_poly
					(pts
						(arc
							(start 0.3048 0.2032)
							(mid 0.275042 0.275042)
							(end 0.2032 0.3048)
						)
						(arc
							(start -0.2032 0.3048)
							(mid -0.275042 0.275042)
							(end -0.3048 0.2032)
						)
						(arc
							(start -0.3048 -0.2032)
							(mid -0.275042 -0.275042)
							(end -0.2032 -0.3048)
						)
						(arc
							(start 0.2032 -0.3048)
							(mid 0.275042 -0.275042)
							(end 0.3048 -0.2032)
						)
					)
					(width 0)
					(fill yes)
				)
			)
		)
	)
	(footprint ""
		(layer "B.Cu")
		(at 54.2036 -163.1188 -90)
		(property "Reference" "R401"
			(at 0 0 90)
			(layer "B.SilkS")
			(hide yes)
			(effects
				(font
					(size 1.27 1.27)
				)
				(justify mirror)
			)
		)
		(property "Value" "7K87R2F-GP"
			(at -0.064008 -3.993896 270)
			(unlocked yes)
			(layer "B.Fab")
			(hide yes)
			(effects
				(font
					(size 1.016 1.016)
					(thickness 0.1524)
				)
				(justify mirror)
			)
		)
		(property "Device Type" "R402H16"
			(at -0.064008 -5.517896 270)
			(unlocked yes)
			(layer "B.Fab")
			(hide yes)
			(effects
				(font
					(size 1.016 1.016)
					(thickness 0.1524)
				)
				(justify mirror)
			)
		)
		(duplicate_pad_numbers_are_jumpers no)
		(fp_line
			(start -0.508 -0.9398)
			(end 0.508 -0.9398)
			(stroke
				(width 0.1524)
				(type default)
			)
			(layer "B.SilkS")
		)
		(fp_line
			(start 0.508 -0.9398)
			(end 0.508 0.9398)
			(stroke
				(width 0.1524)
				(type default)
			)
			(layer "B.SilkS")
		)
		(fp_rect
			(start 0.508 0.9398)
			(end -0.508 -0.9398)
			(stroke
				(width 0)
				(type default)
			)
			(fill no)
			(layer "B.CrtYd")
		)
		(fp_rect
			(start 0.508 0.9398)
			(end -0.508 -0.9398)
			(stroke
				(width 0)
				(type default)
			)
			(fill no)
			(layer "B.Fab")
		)
		(pad "1" smd custom
			(at 0 -0.4445 90)
			(size 0.1397 0.1397)
			(layers "B.Cu" "B.Mask" "B.Paste")
			(net "P12V_STBY")
			(options
				(clearance outline)
				(anchor circle)
			)
			(primitives
				(gr_poly
					(pts
						(arc
							(start -0.1778 0.2794)
							(mid -0.249642 0.249642)
							(end -0.2794 0.1778)
						)
						(arc
							(start -0.2794 -0.1778)
							(mid -0.249642 -0.249642)
							(end -0.1778 -0.2794)
						)
						(arc
							(start 0.1778 -0.2794)
							(mid 0.249642 -0.249642)
							(end 0.2794 -0.1778)
						)
						(arc
							(start 0.2794 0.1778)
							(mid 0.249642 0.249642)
							(end 0.1778 0.2794)
						)
					)
					(width 0)
					(fill yes)
				)
			)
		)
		(pad "2" smd custom
			(at 0 0.4445 90)
			(size 0.1397 0.1397)
			(layers "B.Cu" "B.Mask" "B.Paste")
			(net "ADC_12V")
			(options
				(clearance outline)
				(anchor circle)
			)
			(primitives
				(gr_poly
					(pts
						(arc
							(start -0.1778 0.2794)
							(mid -0.249642 0.249642)
							(end -0.2794 0.1778)
						)
						(arc
							(start -0.2794 -0.1778)
							(mid -0.249642 -0.249642)
							(end -0.1778 -0.2794)
						)
						(arc
							(start 0.1778 -0.2794)
							(mid 0.249642 -0.249642)
							(end 0.2794 -0.1778)
						)
						(arc
							(start 0.2794 0.1778)
							(mid 0.249642 0.249642)
							(end 0.1778 0.2794)
						)
					)
					(width 0)
					(fill yes)
				)
			)
		)
	)
	(footprint ""
		(layer "B.Cu")
		(at 211.836 -88.138 90)
		(property "Reference" "L18"
			(at 0 0 90)
			(layer "B.SilkS")
			(hide yes)
			(effects
				(font
					(size 1.27 1.27)
				)
				(justify mirror)
			)
		)
		(property "Value" "MPZ2012S601AT-GP"
			(at 0 -4.2418 90)
			(unlocked yes)
			(layer "B.Fab")
			(hide yes)
			(effects
				(font
					(size 1.016 1.016)
					(thickness 0.1524)
				)
				(justify mirror)
			)
		)
		(property "Device Type" "L805H42"
			(at 0 -5.7912 90)
			(unlocked yes)
			(layer "B.Fab")
			(hide yes)
			(effects
				(font
					(size 1.016 1.016)
					(thickness 0.1524)
				)
				(justify mirror)
			)
		)
		(duplicate_pad_numbers_are_jumpers no)
		(fp_line
			(start 0.889 -1.7018)
			(end -0.889 -1.7018)
			(stroke
				(width 0.1524)
				(type default)
			)
			(layer "B.SilkS")
		)
		(fp_line
			(start -0.889 -1.7018)
			(end -0.889 1.7018)
			(stroke
				(width 0.1524)
				(type default)
			)
			(layer "B.SilkS")
		)
		(fp_line
			(start 0.889 1.7018)
			(end 0.889 -1.7018)
			(stroke
				(width 0.1524)
				(type default)
			)
			(layer "B.SilkS")
		)
		(fp_line
			(start -0.889 1.7018)
			(end 0.889 1.7018)
			(stroke
				(width 0.1524)
				(type default)
			)
			(layer "B.SilkS")
		)
		(fp_rect
			(start 0.9652 1.778)
			(end -0.9652 -1.778)
			(stroke
				(width 0)
				(type default)
			)
			(fill no)
			(layer "B.CrtYd")
		)
		(fp_rect
			(start 0.9652 1.778)
			(end -0.9652 -1.778)
			(stroke
				(width 0)
				(type default)
			)
			(fill no)
			(layer "B.Fab")
		)
		(pad "1" smd rect
			(at 0 -0.9652 270)
			(size 1.397 1.143)
			(layers "B.Cu" "B.Mask" "B.Paste")
			(net "SAS0_VDDH")
		)
		(pad "2" smd rect
			(at 0 0.9652 270)
			(size 1.397 1.143)
			(layers "B.Cu" "B.Mask" "B.Paste")
			(net "P1V8")
		)
	)
)
